# S9S_MB_2U (Grand Teton) — schematic netlist excerpt (pin names and nets, part order shuffled) for the footprints in the layout excerpt that follows; sources: Cadence DE-HDL packaged netlist, KiCad conversion of 03242023_DA0F0TMBIJ0_F0T_Motherboard_J_brd_V01_OCP.brd

R2729  Q_RES  33.2 1% CHIP  pkg 0402LF  page 114 : A = PWRGD_CHC_CPU0_DIMM1 ; B = PWRGD_FAIL_CPU0_CD
PC2286  Q_CAP  1000PF 50V 5% EMPTY  pkg 0402  page 262 : A = FM_P1V05_PCH_AUX_R_EN ; B = GND

(kicad_pcb
	(version 20260206)
	(generator "pcbnew")
	(generator_version "10.0")
	(general
		(thickness 1.6)
		(legacy_teardrops no)
	)
	(paper "A4")
	(title_block
		(title "03242023_DA0F0TMBIJ0_F0T_Motherboard_J_brd_V01_OCP.brd")
		(comment 1 "Grand Teton / footprints 4206-4207 of 6105")
	)
	(layers
		(0 "F.Cu" signal "TOP")
		(4 "In1.Cu" signal "GND")
		(6 "In2.Cu" signal "IN1")
		(8 "In3.Cu" signal "GND1")
		(10 "In4.Cu" signal "IN2")
		(12 "In5.Cu" signal "GND2")
		(14 "In6.Cu" signal "IN3")
		(16 "In7.Cu" signal "GND3")
		(18 "In8.Cu" signal "VCC")
		(20 "In9.Cu" signal "VCC1")
		(22 "In10.Cu" signal "GND4")
		(24 "In11.Cu" signal "IN4")
		(26 "In12.Cu" signal "GND5")
		(28 "In13.Cu" signal "IN5")
		(30 "In14.Cu" signal "GND6")
		(32 "In15.Cu" signal "IN6")
		(34 "In16.Cu" signal "GND7")
		(2 "B.Cu" signal "BOTTOM")
		(9 "F.Adhes" user "F.Adhesive")
		(11 "B.Adhes" user "B.Adhesive")
		(13 "F.Paste" user "Package Geometry/Pastemask Top")
		(15 "B.Paste" user "Package Geometry/Pastemask Bottom")
		(5 "F.SilkS" user "Ref Des/Silkscreen Top")
		(7 "B.SilkS" user "Ref Des/Silkscreen Bottom")
		(1 "F.Mask" user "Board Geometry/Soldermask Top")
		(3 "B.Mask" user "Board Geometry/Soldermask Bottom")
		(17 "Dwgs.User" user "User.Drawings")
		(19 "Cmts.User" user "User.Comments")
		(21 "Eco1.User" user "User.Eco1")
		(23 "Eco2.User" user "User.Eco2")
		(25 "Edge.Cuts" user "Board Geometry/Outline")
		(27 "Margin" user)
		(31 "F.CrtYd" user "Package Geometry/Place Bound Top")
		(29 "B.CrtYd" user "Package Geometry/Place Bound Bottom")
		(35 "F.Fab" user "Ref Des/Assembly Top")
		(33 "B.Fab" user "Ref Des/Assembly Bottom")
	)
	(footprint ""
		(layer "B.Cu")
		(at 274.83562 -318.986408 90)
		(property "Reference" "R2729"
			(at 0 0 90)
			(layer "B.SilkS")
			(hide yes)
			(effects
				(font
					(size 1.27 1.27)
				)
				(justify mirror)
			)
		)
		(property "Value" ""
			(at 0 0 90)
			(layer "B.Fab")
			(effects
				(font
					(size 1.27 1.27)
				)
				(justify mirror)
			)
		)
		(duplicate_pad_numbers_are_jumpers no)
		(fp_line
			(start 0.7874 -0.4064)
			(end -0.7874 -0.4064)
			(stroke
				(width 0.1524)
				(type default)
			)
			(layer "B.SilkS")
		)
		(fp_line
			(start -0.7874 -0.4064)
			(end -0.7874 0.4064)
			(stroke
				(width 0.1524)
				(type default)
			)
			(layer "B.SilkS")
		)
		(fp_line
			(start 0.7874 0.4064)
			(end 0.7874 -0.4064)
			(stroke
				(width 0.1524)
				(type default)
			)
			(layer "B.SilkS")
		)
		(fp_line
			(start -0.7874 0.4064)
			(end 0.7874 0.4064)
			(stroke
				(width 0.1524)
				(type default)
			)
			(layer "B.SilkS")
		)
		(fp_line
			(start 0.67945 -0.305054)
			(end 0.12065 -0.305054)
			(stroke
				(width 0.1)
				(type default)
			)
			(layer "B.Fab")
		)
		(fp_line
			(start 0.12065 -0.305054)
			(end 0.12065 -0.2794)
			(stroke
				(width 0.1)
				(type default)
			)
			(layer "B.Fab")
		)
		(fp_line
			(start -0.12065 -0.3048)
			(end -0.67945 -0.3048)
			(stroke
				(width 0.1)
				(type default)
			)
			(layer "B.Fab")
		)
		(fp_line
			(start -0.67945 -0.3048)
			(end -0.67945 0.3048)
			(stroke
				(width 0.1)
				(type default)
			)
			(layer "B.Fab")
		)
		(fp_line
			(start 0.12065 -0.2794)
			(end -0.12065 -0.2794)
			(stroke
				(width 0.1)
				(type default)
			)
			(layer "B.Fab")
		)
		(fp_line
			(start -0.12065 -0.2794)
			(end -0.12065 -0.3048)
			(stroke
				(width 0.1)
				(type default)
			)
			(layer "B.Fab")
		)
		(fp_line
			(start 0.12065 0.2794)
			(end 0.12065 0.3048)
			(stroke
				(width 0.1)
				(type default)
			)
			(layer "B.Fab")
		)
		(fp_line
			(start -0.120396 0.2794)
			(end 0.12065 0.2794)
			(stroke
				(width 0.1)
				(type default)
			)
			(layer "B.Fab")
		)
		(fp_line
			(start 0.67945 0.3048)
			(end 0.67945 -0.305054)
			(stroke
				(width 0.1)
				(type default)
			)
			(layer "B.Fab")
		)
		(fp_line
			(start 0.12065 0.3048)
			(end 0.67945 0.3048)
			(stroke
				(width 0.1)
				(type default)
			)
			(layer "B.Fab")
		)
		(fp_line
			(start -0.120396 0.3048)
			(end -0.120396 0.2794)
			(stroke
				(width 0.1)
				(type default)
			)
			(layer "B.Fab")
		)
		(fp_line
			(start -0.67945 0.3048)
			(end -0.120396 0.3048)
			(stroke
				(width 0.1)
				(type default)
			)
			(layer "B.Fab")
		)
		(pad "1" smd circle
			(at 0.40005 0 270)
			(size 0 0)
			(layers "B.Cu" "B.Mask" "B.Paste")
			(net "PWRGD_CHC_CPU0_DIMM1")
		)
		(pad "2" smd circle
			(at -0.40005 0 270)
			(size 0 0)
			(layers "B.Cu" "B.Mask" "B.Paste")
			(net "PWRGD_FAIL_CPU0_CD")
		)
	)
	(footprint ""
		(layer "B.Cu")
		(at 260.121146 -76.558902 -90)
		(property "Reference" "PC2286"
			(at 0 0 90)
			(layer "B.SilkS")
			(hide yes)
			(effects
				(font
					(size 1.27 1.27)
				)
				(justify mirror)
			)
		)
		(property "Value" ""
			(at 0 0 90)
			(layer "B.Fab")
			(effects
				(font
					(size 1.27 1.27)
				)
				(justify mirror)
			)
		)
		(duplicate_pad_numbers_are_jumpers no)
		(fp_line
			(start -0.7874 0.4064)
			(end 0.7874 0.4064)
			(stroke
				(width 0.1524)
				(type default)
			)
			(layer "B.SilkS")
		)
		(fp_line
			(start 0.7874 0.4064)
			(end 0.7874 -0.4064)
			(stroke
				(width 0.1524)
				(type default)
			)
			(layer "B.SilkS")
		)
		(fp_line
			(start -0.7874 -0.4064)
			(end -0.7874 0.4064)
			(stroke
				(width 0.1524)
				(type default)
			)
			(layer "B.SilkS")
		)
		(fp_line
			(start 0.7874 -0.4064)
			(end -0.7874 -0.4064)
			(stroke
				(width 0.1524)
				(type default)
			)
			(layer "B.SilkS")
		)
		(fp_line
			(start -0.67945 0.3048)
			(end -0.120396 0.3048)
			(stroke
				(width 0.1)
				(type default)
			)
			(layer "B.Fab")
		)
		(fp_line
			(start -0.120396 0.3048)
			(end -0.120396 0.2794)
			(stroke
				(width 0.1)
				(type default)
			)
			(layer "B.Fab")
		)
		(fp_line
			(start 0.12065 0.3048)
			(end 0.67945 0.3048)
			(stroke
				(width 0.1)
				(type default)
			)
			(layer "B.Fab")
		)
		(fp_line
			(start 0.67945 0.3048)
			(end 0.67945 -0.305054)
			(stroke
				(width 0.1)
				(type default)
			)
			(layer "B.Fab")
		)
		(fp_line
			(start -0.120396 0.2794)
			(end 0.12065 0.2794)
			(stroke
				(width 0.1)
				(type default)
			)
			(layer "B.Fab")
		)
		(fp_line
			(start 0.12065 0.2794)
			(end 0.12065 0.3048)
			(stroke
				(width 0.1)
				(type default)
			)
			(layer "B.Fab")
		)
		(fp_line
			(start -0.12065 -0.2794)
			(end -0.12065 -0.3048)
			(stroke
				(width 0.1)
				(type default)
			)
			(layer "B.Fab")
		)
		(fp_line
			(start 0.12065 -0.2794)
			(end -0.12065 -0.2794)
			(stroke
				(width 0.1)
				(type default)
			)
			(layer "B.Fab")
		)
		(fp_line
			(start -0.67945 -0.3048)
			(end -0.67945 0.3048)
			(stroke
				(width 0.1)
				(type default)
			)
			(layer "B.Fab")
		)
		(fp_line
			(start -0.12065 -0.3048)
			(end -0.67945 -0.3048)
			(stroke
				(width 0.1)
				(type default)
			)
			(layer "B.Fab")
		)
		(fp_line
			(start 0.12065 -0.305054)
			(end 0.12065 -0.2794)
			(stroke
				(width 0.1)
				(type default)
			)
			(layer "B.Fab")
		)
		(fp_line
			(start 0.67945 -0.305054)
			(end 0.12065 -0.305054)
			(stroke
				(width 0.1)
				(type default)
			)
			(layer "B.Fab")
		)
		(pad "1" smd circle
			(at 0.40005 0 90)
			(size 0 0)
			(layers "B.Cu" "B.Mask" "B.Paste")
			(net "FM_P1V05_PCH_AUX_R_EN")
		)
		(pad "2" smd circle
			(at -0.40005 0 90)
			(size 0 0)
			(layers "B.Cu" "B.Mask" "B.Paste")
			(net "GND")
		)
	)
)
